(kicad_pcb
	(version 20260206)
	(generator "pcbnew")
	(generator_version "10.0")
	(general
		(thickness 1.6)
		(legacy_teardrops no)
	)
	(paper "A4")
	(title_block
		(title "04192023_DAF0TMB3IC0_F0TG_MB_C_brd_V02_OCP.brd")
		(comment 1 "Grand Teton / footprints 8135-8142 of 8354")
	)
	(layers
		(0 "F.Cu" signal "TOP")
		(4 "In1.Cu" signal "GND")
		(6 "In2.Cu" signal "IN1")
		(8 "In3.Cu" signal "GND1")
		(10 "In4.Cu" signal "IN2")
		(12 "In5.Cu" signal "GND2")
		(14 "In6.Cu" signal "IN3")
		(16 "In7.Cu" signal "GND3")
		(18 "In8.Cu" signal "VCC")
		(20 "In9.Cu" signal "VCC1")
		(22 "In10.Cu" signal "GND4")
		(24 "In11.Cu" signal "IN4")
		(26 "In12.Cu" signal "GND5")
		(28 "In13.Cu" signal "IN5")
		(30 "In14.Cu" signal "GND6")
		(32 "In15.Cu" signal "IN6")
		(34 "In16.Cu" signal "GND7")
		(2 "B.Cu" signal "BOTTOM")
		(9 "F.Adhes" user "F.Adhesive")
		(11 "B.Adhes" user "B.Adhesive")
		(13 "F.Paste" user "Package Geometry/Pastemask Top")
		(15 "B.Paste" user "Package Geometry/Pastemask Bottom")
		(5 "F.SilkS" user "Ref Des/Silkscreen Top")
		(7 "B.SilkS" user "Ref Des/Silkscreen Bottom")
		(1 "F.Mask" user "Board Geometry/Soldermask Top")
		(3 "B.Mask" user "Board Geometry/Soldermask Bottom")
		(17 "Dwgs.User" user "User.Drawings")
		(19 "Cmts.User" user "User.Comments")
		(21 "Eco1.User" user "User.Eco1")
		(23 "Eco2.User" user "User.Eco2")
		(25 "Edge.Cuts" user "Board Geometry/Outline")
		(27 "Margin" user)
		(31 "F.CrtYd" user "Package Geometry/Place Bound Top")
		(29 "B.CrtYd" user "Package Geometry/Place Bound Bottom")
		(35 "F.Fab" user "Ref Des/Assembly Top")
		(33 "B.Fab" user "Ref Des/Assembly Bottom")
	)
	(footprint ""
		(layer "B.Cu")
		(at 167.132 -116.296948 180)
		(property "Reference" "R888"
			(at 0 0 0)
			(layer "B.SilkS")
			(hide yes)
			(effects
				(font
					(size 1.27 1.27)
				)
				(justify mirror)
			)
		)
		(property "Value" ""
			(at 0 0 0)
			(layer "B.Fab")
			(effects
				(font
					(size 1.27 1.27)
				)
				(justify mirror)
			)
		)
		(duplicate_pad_numbers_are_jumpers no)
		(fp_line
			(start 0.7874 0.4064)
			(end 0.7874 -0.4064)
			(stroke
				(width 0.1524)
				(type default)
			)
			(layer "B.SilkS")
		)
		(fp_line
			(start 0.7874 -0.4064)
			(end -0.7874 -0.4064)
			(stroke
				(width 0.1524)
				(type default)
			)
			(layer "B.SilkS")
		)
		(fp_line
			(start -0.7874 0.4064)
			(end 0.7874 0.4064)
			(stroke
				(width 0.1524)
				(type default)
			)
			(layer "B.SilkS")
		)
		(fp_line
			(start -0.7874 -0.4064)
			(end -0.7874 0.4064)
			(stroke
				(width 0.1524)
				(type default)
			)
			(layer "B.SilkS")
		)
		(fp_line
			(start 0.67945 0.3048)
			(end 0.67945 -0.305054)
			(stroke
				(width 0.1)
				(type default)
			)
			(layer "B.Fab")
		)
		(fp_line
			(start 0.67945 -0.305054)
			(end 0.12065 -0.305054)
			(stroke
				(width 0.1)
				(type default)
			)
			(layer "B.Fab")
		)
		(fp_line
			(start 0.12065 0.3048)
			(end 0.67945 0.3048)
			(stroke
				(width 0.1)
				(type default)
			)
			(layer "B.Fab")
		)
		(fp_line
			(start 0.12065 0.2794)
			(end 0.12065 0.3048)
			(stroke
				(width 0.1)
				(type default)
			)
			(layer "B.Fab")
		)
		(fp_line
			(start 0.12065 -0.2794)
			(end -0.12065 -0.2794)
			(stroke
				(width 0.1)
				(type default)
			)
			(layer "B.Fab")
		)
		(fp_line
			(start 0.12065 -0.305054)
			(end 0.12065 -0.2794)
			(stroke
				(width 0.1)
				(type default)
			)
			(layer "B.Fab")
		)
		(fp_line
			(start -0.120396 0.3048)
			(end -0.120396 0.2794)
			(stroke
				(width 0.1)
				(type default)
			)
			(layer "B.Fab")
		)
		(fp_line
			(start -0.120396 0.2794)
			(end 0.12065 0.2794)
			(stroke
				(width 0.1)
				(type default)
			)
			(layer "B.Fab")
		)
		(fp_line
			(start -0.12065 -0.2794)
			(end -0.12065 -0.3048)
			(stroke
				(width 0.1)
				(type default)
			)
			(layer "B.Fab")
		)
		(fp_line
			(start -0.12065 -0.3048)
			(end -0.67945 -0.3048)
			(stroke
				(width 0.1)
				(type default)
			)
			(layer "B.Fab")
		)
		(fp_line
			(start -0.67945 0.3048)
			(end -0.120396 0.3048)
			(stroke
				(width 0.1)
				(type default)
			)
			(layer "B.Fab")
		)
		(fp_line
			(start -0.67945 -0.3048)
			(end -0.67945 0.3048)
			(stroke
				(width 0.1)
				(type default)
			)
			(layer "B.Fab")
		)
		(pad "1" smd circle
			(at 0.40005 0)
			(size 0 0)
			(layers "B.Cu" "B.Mask" "B.Paste")
			(net "P3V3_AUX")
		)
		(pad "2" smd circle
			(at -0.40005 0)
			(size 0 0)
			(layers "B.Cu" "B.Mask" "B.Paste")
			(net "SCM_SPARE_0")
		)
	)
	(footprint ""
		(layer "B.Cu")
		(at 214.122 -338.582)
		(property "Reference" "R914"
			(at 0 0 0)
			(layer "B.SilkS")
			(hide yes)
			(effects
				(font
					(size 1.27 1.27)
				)
				(justify mirror)
			)
		)
		(property "Value" ""
			(at 0 0 0)
			(layer "B.Fab")
			(effects
				(font
					(size 1.27 1.27)
				)
				(justify mirror)
			)
		)
		(duplicate_pad_numbers_are_jumpers no)
		(fp_line
			(start -0.32512 -0.175006)
			(end -0.32512 0.175006)
			(stroke
				(width 0.1)
				(type default)
			)
			(layer "B.Fab")
		)
		(fp_line
			(start -0.32512 0.175006)
			(end 0.32512 0.175006)
			(stroke
				(width 0.1)
				(type default)
			)
			(layer "B.Fab")
		)
		(fp_line
			(start 0.32512 -0.175006)
			(end -0.32512 -0.175006)
			(stroke
				(width 0.1)
				(type default)
			)
			(layer "B.Fab")
		)
		(fp_line
			(start 0.32512 0.175006)
			(end 0.32512 -0.175006)
			(stroke
				(width 0.1)
				(type default)
			)
			(layer "B.Fab")
		)
		(pad "1" smd rect
			(at 0.2667 0 180)
			(size 0.3048 0.381)
			(layers "B.Cu" "B.Mask" "B.Paste")
			(net "SMB_RT_CPU1_P3_R_SDA")
		)
		(pad "2" smd rect
			(at -0.2667 0)
			(size 0.3048 0.381)
			(layers "B.Cu" "B.Mask" "B.Paste")
			(net "SMB_RT_CPU1_P3_R2_SDA")
		)
	)
	(footprint ""
		(layer "B.Cu")
		(at 166.473124 -424.821604 -90)
		(property "Reference" "R1212"
			(at 0 0 90)
			(layer "B.SilkS")
			(hide yes)
			(effects
				(font
					(size 1.27 1.27)
				)
				(justify mirror)
			)
		)
		(property "Value" ""
			(at 0 0 90)
			(layer "B.Fab")
			(effects
				(font
					(size 1.27 1.27)
				)
				(justify mirror)
			)
		)
		(duplicate_pad_numbers_are_jumpers no)
		(fp_line
			(start -0.32512 0.175006)
			(end 0.32512 0.175006)
			(stroke
				(width 0.1)
				(type default)
			)
			(layer "B.Fab")
		)
		(fp_line
			(start 0.32512 0.175006)
			(end 0.32512 -0.175006)
			(stroke
				(width 0.1)
				(type default)
			)
			(layer "B.Fab")
		)
		(fp_line
			(start -0.32512 -0.175006)
			(end -0.32512 0.175006)
			(stroke
				(width 0.1)
				(type default)
			)
			(layer "B.Fab")
		)
		(fp_line
			(start 0.32512 -0.175006)
			(end -0.32512 -0.175006)
			(stroke
				(width 0.1)
				(type default)
			)
			(layer "B.Fab")
		)
		(pad "1" smd rect
			(at 0.2667 0 90)
			(size 0.3048 0.381)
			(layers "B.Cu" "B.Mask" "B.Paste")
			(net "GND")
		)
		(pad "2" smd rect
			(at -0.2667 0 270)
			(size 0.3048 0.381)
			(layers "B.Cu" "B.Mask" "B.Paste")
			(net "RT_ROM_MUX3_OE_N")
		)
	)
	(footprint ""
		(layer "B.Cu")
		(at 167.132 -119.344948 180)
		(property "Reference" "R63"
			(at 0 0 0)
			(layer "B.SilkS")
			(hide yes)
			(effects
				(font
					(size 1.27 1.27)
				)
				(justify mirror)
			)
		)
		(property "Value" ""
			(at 0 0 0)
			(layer "B.Fab")
			(effects
				(font
					(size 1.27 1.27)
				)
				(justify mirror)
			)
		)
		(duplicate_pad_numbers_are_jumpers no)
		(fp_line
			(start 0.7874 0.4064)
			(end 0.7874 -0.4064)
			(stroke
				(width 0.1524)
				(type default)
			)
			(layer "B.SilkS")
		)
		(fp_line
			(start 0.7874 -0.4064)
			(end -0.7874 -0.4064)
			(stroke
				(width 0.1524)
				(type default)
			)
			(layer "B.SilkS")
		)
		(fp_line
			(start -0.7874 0.4064)
			(end 0.7874 0.4064)
			(stroke
				(width 0.1524)
				(type default)
			)
			(layer "B.SilkS")
		)
		(fp_line
			(start -0.7874 -0.4064)
			(end -0.7874 0.4064)
			(stroke
				(width 0.1524)
				(type default)
			)
			(layer "B.SilkS")
		)
		(fp_line
			(start 0.67945 0.3048)
			(end 0.67945 -0.305054)
			(stroke
				(width 0.1)
				(type default)
			)
			(layer "B.Fab")
		)
		(fp_line
			(start 0.67945 -0.305054)
			(end 0.12065 -0.305054)
			(stroke
				(width 0.1)
				(type default)
			)
			(layer "B.Fab")
		)
		(fp_line
			(start 0.12065 0.3048)
			(end 0.67945 0.3048)
			(stroke
				(width 0.1)
				(type default)
			)
			(layer "B.Fab")
		)
		(fp_line
			(start 0.12065 0.2794)
			(end 0.12065 0.3048)
			(stroke
				(width 0.1)
				(type default)
			)
			(layer "B.Fab")
		)
		(fp_line
			(start 0.12065 -0.2794)
			(end -0.12065 -0.2794)
			(stroke
				(width 0.1)
				(type default)
			)
			(layer "B.Fab")
		)
		(fp_line
			(start 0.12065 -0.305054)
			(end 0.12065 -0.2794)
			(stroke
				(width 0.1)
				(type default)
			)
			(layer "B.Fab")
		)
		(fp_line
			(start -0.120396 0.3048)
			(end -0.120396 0.2794)
			(stroke
				(width 0.1)
				(type default)
			)
			(layer "B.Fab")
		)
		(fp_line
			(start -0.120396 0.2794)
			(end 0.12065 0.2794)
			(stroke
				(width 0.1)
				(type default)
			)
			(layer "B.Fab")
		)
		(fp_line
			(start -0.12065 -0.2794)
			(end -0.12065 -0.3048)
			(stroke
				(width 0.1)
				(type default)
			)
			(layer "B.Fab")
		)
		(fp_line
			(start -0.12065 -0.3048)
			(end -0.67945 -0.3048)
			(stroke
				(width 0.1)
				(type default)
			)
			(layer "B.Fab")
		)
		(fp_line
			(start -0.67945 0.3048)
			(end -0.120396 0.3048)
			(stroke
				(width 0.1)
				(type default)
			)
			(layer "B.Fab")
		)
		(fp_line
			(start -0.67945 -0.3048)
			(end -0.67945 0.3048)
			(stroke
				(width 0.1)
				(type default)
			)
			(layer "B.Fab")
		)
		(pad "1" smd circle
			(at 0.40005 0)
			(size 0 0)
			(layers "B.Cu" "B.Mask" "B.Paste")
			(net "SCM_SYS_PWROK_R")
		)
		(pad "2" smd circle
			(at -0.40005 0)
			(size 0 0)
			(layers "B.Cu" "B.Mask" "B.Paste")
			(net "SCM_SYS_PWROK")
		)
	)
	(footprint ""
		(layer "B.Cu")
		(at 241.140488 -331.597 180)
		(property "Reference" "R843"
			(at 0 0 0)
			(layer "B.SilkS")
			(hide yes)
			(effects
				(font
					(size 1.27 1.27)
				)
				(justify mirror)
			)
		)
		(property "Value" ""
			(at 0 0 0)
			(layer "B.Fab")
			(effects
				(font
					(size 1.27 1.27)
				)
				(justify mirror)
			)
		)
		(duplicate_pad_numbers_are_jumpers no)
		(fp_line
			(start 0.32512 0.175006)
			(end 0.32512 -0.175006)
			(stroke
				(width 0.1)
				(type default)
			)
			(layer "B.Fab")
		)
		(fp_line
			(start 0.32512 -0.175006)
			(end -0.32512 -0.175006)
			(stroke
				(width 0.1)
				(type default)
			)
			(layer "B.Fab")
		)
		(fp_line
			(start -0.32512 0.175006)
			(end 0.32512 0.175006)
			(stroke
				(width 0.1)
				(type default)
			)
			(layer "B.Fab")
		)
		(fp_line
			(start -0.32512 -0.175006)
			(end -0.32512 0.175006)
			(stroke
				(width 0.1)
				(type default)
			)
			(layer "B.Fab")
		)
		(pad "1" smd rect
			(at 0.2667 0)
			(size 0.3048 0.381)
			(layers "B.Cu" "B.Mask" "B.Paste")
			(net "P1V8_AUX")
		)
		(pad "2" smd rect
			(at -0.2667 0 180)
			(size 0.3048 0.381)
			(layers "B.Cu" "B.Mask" "B.Paste")
			(net "RT_ROM_SMB_MUX_ADDR1")
		)
	)
	(footprint ""
		(layer "B.Cu")
		(at 428.087282 -438.192672 90)
		(property "Reference" "R4169"
			(at 0 0 90)
			(layer "B.SilkS")
			(hide yes)
			(effects
				(font
					(size 1.27 1.27)
				)
				(justify mirror)
			)
		)
		(property "Value" ""
			(at 0 0 90)
			(layer "B.Fab")
			(effects
				(font
					(size 1.27 1.27)
				)
				(justify mirror)
			)
		)
		(duplicate_pad_numbers_are_jumpers no)
		(fp_line
			(start 0.7874 -0.4064)
			(end -0.7874 -0.4064)
			(stroke
				(width 0.1524)
				(type default)
			)
			(layer "B.SilkS")
		)
		(fp_line
			(start -0.7874 -0.4064)
			(end -0.7874 0.4064)
			(stroke
				(width 0.1524)
				(type default)
			)
			(layer "B.SilkS")
		)
		(fp_line
			(start 0.7874 0.4064)
			(end 0.7874 -0.4064)
			(stroke
				(width 0.1524)
				(type default)
			)
			(layer "B.SilkS")
		)
		(fp_line
			(start -0.7874 0.4064)
			(end 0.7874 0.4064)
			(stroke
				(width 0.1524)
				(type default)
			)
			(layer "B.SilkS")
		)
		(fp_line
			(start 0.67945 -0.305054)
			(end 0.12065 -0.305054)
			(stroke
				(width 0.1)
				(type default)
			)
			(layer "B.Fab")
		)
		(fp_line
			(start 0.12065 -0.305054)
			(end 0.12065 -0.2794)
			(stroke
				(width 0.1)
				(type default)
			)
			(layer "B.Fab")
		)
		(fp_line
			(start -0.12065 -0.3048)
			(end -0.67945 -0.3048)
			(stroke
				(width 0.1)
				(type default)
			)
			(layer "B.Fab")
		)
		(fp_line
			(start -0.67945 -0.3048)
			(end -0.67945 0.3048)
			(stroke
				(width 0.1)
				(type default)
			)
			(layer "B.Fab")
		)
		(fp_line
			(start 0.12065 -0.2794)
			(end -0.12065 -0.2794)
			(stroke
				(width 0.1)
				(type default)
			)
			(layer "B.Fab")
		)
		(fp_line
			(start -0.12065 -0.2794)
			(end -0.12065 -0.3048)
			(stroke
				(width 0.1)
				(type default)
			)
			(layer "B.Fab")
		)
		(fp_line
			(start 0.12065 0.2794)
			(end 0.12065 0.3048)
			(stroke
				(width 0.1)
				(type default)
			)
			(layer "B.Fab")
		)
		(fp_line
			(start -0.120396 0.2794)
			(end 0.12065 0.2794)
			(stroke
				(width 0.1)
				(type default)
			)
			(layer "B.Fab")
		)
		(fp_line
			(start 0.67945 0.3048)
			(end 0.67945 -0.305054)
			(stroke
				(width 0.1)
				(type default)
			)
			(layer "B.Fab")
		)
		(fp_line
			(start 0.12065 0.3048)
			(end 0.67945 0.3048)
			(stroke
				(width 0.1)
				(type default)
			)
			(layer "B.Fab")
		)
		(fp_line
			(start -0.120396 0.3048)
			(end -0.120396 0.2794)
			(stroke
				(width 0.1)
				(type default)
			)
			(layer "B.Fab")
		)
		(fp_line
			(start -0.67945 0.3048)
			(end -0.120396 0.3048)
			(stroke
				(width 0.1)
				(type default)
			)
			(layer "B.Fab")
		)
		(pad "1" smd circle
			(at 0.40005 0 270)
			(size 0 0)
			(layers "B.Cu" "B.Mask" "B.Paste")
			(net "P3V3_AUX")
		)
		(pad "2" smd circle
			(at -0.40005 0 270)
			(size 0 0)
			(layers "B.Cu" "B.Mask" "B.Paste")
			(net "GPU_3V3IO_RSVD3_ISO")
		)
	)
	(footprint ""
		(layer "B.Cu")
		(at 109.895386 -253.432564)
		(property "Reference" "C2466"
			(at 0 0 0)
			(layer "B.SilkS")
			(hide yes)
			(effects
				(font
					(size 1.27 1.27)
				)
				(justify mirror)
			)
		)
		(property "Value" ""
			(at 0 0 0)
			(layer "B.Fab")
			(effects
				(font
					(size 1.27 1.27)
				)
				(justify mirror)
			)
		)
		(duplicate_pad_numbers_are_jumpers no)
		(fp_line
			(start -0.7874 -0.4064)
			(end -0.7874 0.4064)
			(stroke
				(width 0.1524)
				(type default)
			)
			(layer "B.SilkS")
		)
		(fp_line
			(start -0.7874 0.4064)
			(end 0.7874 0.4064)
			(stroke
				(width 0.1524)
				(type default)
			)
			(layer "B.SilkS")
		)
		(fp_line
			(start 0.7874 -0.4064)
			(end -0.7874 -0.4064)
			(stroke
				(width 0.1524)
				(type default)
			)
			(layer "B.SilkS")
		)
		(fp_line
			(start 0.7874 0.4064)
			(end 0.7874 -0.4064)
			(stroke
				(width 0.1524)
				(type default)
			)
			(layer "B.SilkS")
		)
		(fp_line
			(start -0.67945 -0.3048)
			(end -0.67945 0.3048)
			(stroke
				(width 0.1)
				(type default)
			)
			(layer "B.Fab")
		)
		(fp_line
			(start -0.67945 0.3048)
			(end -0.120396 0.3048)
			(stroke
				(width 0.1)
				(type default)
			)
			(layer "B.Fab")
		)
		(fp_line
			(start -0.12065 -0.3048)
			(end -0.67945 -0.3048)
			(stroke
				(width 0.1)
				(type default)
			)
			(layer "B.Fab")
		)
		(fp_line
			(start -0.12065 -0.2794)
			(end -0.12065 -0.3048)
			(stroke
				(width 0.1)
				(type default)
			)
			(layer "B.Fab")
		)
		(fp_line
			(start -0.120396 0.2794)
			(end 0.12065 0.2794)
			(stroke
				(width 0.1)
				(type default)
			)
			(layer "B.Fab")
		)
		(fp_line
			(start -0.120396 0.3048)
			(end -0.120396 0.2794)
			(stroke
				(width 0.1)
				(type default)
			)
			(layer "B.Fab")
		)
		(fp_line
			(start 0.12065 -0.305054)
			(end 0.12065 -0.2794)
			(stroke
				(width 0.1)
				(type default)
			)
			(layer "B.Fab")
		)
		(fp_line
			(start 0.12065 -0.2794)
			(end -0.12065 -0.2794)
			(stroke
				(width 0.1)
				(type default)
			)
			(layer "B.Fab")
		)
		(fp_line
			(start 0.12065 0.2794)
			(end 0.12065 0.3048)
			(stroke
				(width 0.1)
				(type default)
			)
			(layer "B.Fab")
		)
		(fp_line
			(start 0.12065 0.3048)
			(end 0.67945 0.3048)
			(stroke
				(width 0.1)
				(type default)
			)
			(layer "B.Fab")
		)
		(fp_line
			(start 0.67945 -0.305054)
			(end 0.12065 -0.305054)
			(stroke
				(width 0.1)
				(type default)
			)
			(layer "B.Fab")
		)
		(fp_line
			(start 0.67945 0.3048)
			(end 0.67945 -0.305054)
			(stroke
				(width 0.1)
				(type default)
			)
			(layer "B.Fab")
		)
		(pad "1" smd circle
			(at 0.40005 0 180)
			(size 0 0)
			(layers "B.Cu" "B.Mask" "B.Paste")
			(net "PVDDCR_SOC_P1")
		)
		(pad "2" smd circle
			(at -0.40005 0 180)
			(size 0 0)
			(layers "B.Cu" "B.Mask" "B.Paste")
			(net "GND")
		)
	)
	(footprint ""
		(layer "B.Cu")
		(at 94.373954 -191.358012 90)
		(property "Reference" "PC282_2"
			(at 0 0 90)
			(layer "B.SilkS")
			(hide yes)
			(effects
				(font
					(size 1.27 1.27)
				)
				(justify mirror)
			)
		)
		(property "Value" ""
			(at 0 0 90)
			(layer "B.Fab")
			(effects
				(font
					(size 1.27 1.27)
				)
				(justify mirror)
			)
		)
		(duplicate_pad_numbers_are_jumpers no)
		(fp_line
			(start 1.524 -0.762)
			(end -1.524 -0.762)
			(stroke
				(width 0.1524)
				(type default)
			)
			(layer "B.SilkS")
		)
		(fp_line
			(start -1.524 -0.762)
			(end -1.524 0.762)
			(stroke
				(width 0.1524)
				(type default)
			)
			(layer "B.SilkS")
		)
		(fp_line
			(start 1.524 0.762)
			(end 1.524 -0.762)
			(stroke
				(width 0.1524)
				(type default)
			)
			(layer "B.SilkS")
		)
		(fp_line
			(start -1.524 0.762)
			(end 1.524 0.762)
			(stroke
				(width 0.1524)
				(type default)
			)
			(layer "B.SilkS")
		)
		(fp_line
			(start 1.1049 -0.724916)
			(end 1.1049 0.724916)
			(stroke
				(width 0.1)
				(type default)
			)
			(layer "B.Fab")
		)
		(fp_line
			(start -1.1049 -0.724916)
			(end 1.1049 -0.724916)
			(stroke
				(width 0.1)
				(type default)
			)
			(layer "B.Fab")
		)
		(fp_line
			(start 1.1049 0.724916)
			(end -1.1049 0.724916)
			(stroke
				(width 0.1)
				(type default)
			)
			(layer "B.Fab")
		)
		(fp_line
			(start -1.1049 0.724916)
			(end -1.1049 -0.724916)
			(stroke
				(width 0.1)
				(type default)
			)
			(layer "B.Fab")
		)
		(pad "1" smd rect
			(at 0.889 0 90)
			(size 1.016 1.27)
			(layers "B.Cu" "B.Mask" "B.Paste")
			(net "PVDDCR_CPU0_P1")
		)
		(pad "2" smd rect
			(at -0.889 0 90)
			(size 1.016 1.27)
			(layers "B.Cu" "B.Mask" "B.Paste")
			(net "GND")
		)
	)
)
